(kicad_pcb
	(version 20260206)
	(generator "pcbnew")
	(generator_version "10.0")
	(general
		(thickness 1.6)
		(legacy_teardrops no)
	)
	(paper "A4")
	(title_block
		(title "01162023_DA0F0TEBIF0_F0T_Expander_BD_F_brd_V02_OCP.brd")
		(comment 1 "Grand Teton / footprints 9283-9292 of 9728")
	)
	(layers
		(0 "F.Cu" signal "TOP")
		(4 "In1.Cu" signal "GND")
		(6 "In2.Cu" signal "VCC")
		(8 "In3.Cu" signal "VCC1")
		(10 "In4.Cu" signal "GND1")
		(12 "In5.Cu" signal "IN1")
		(14 "In6.Cu" signal "GND2")
		(16 "In7.Cu" signal "IN2")
		(18 "In8.Cu" signal "GND3")
		(20 "In9.Cu" signal "IN3")
		(22 "In10.Cu" signal "GND4")
		(24 "In11.Cu" signal "IN4")
		(26 "In12.Cu" signal "GND5")
		(28 "In13.Cu" signal "IN5")
		(30 "In14.Cu" signal "GND6")
		(32 "In15.Cu" signal "IN6")
		(34 "In16.Cu" signal "GND7")
		(2 "B.Cu" signal "BOTTOM")
		(9 "F.Adhes" user "F.Adhesive")
		(11 "B.Adhes" user "B.Adhesive")
		(13 "F.Paste" user "Package Geometry/Pastemask Top")
		(15 "B.Paste" user "Package Geometry/Pastemask Bottom")
		(5 "F.SilkS" user "Ref Des/Silkscreen Top")
		(7 "B.SilkS" user "Ref Des/Silkscreen Bottom")
		(1 "F.Mask" user "Board Geometry/Soldermask Top")
		(3 "B.Mask" user "Board Geometry/Soldermask Bottom")
		(17 "Dwgs.User" user "User.Drawings")
		(19 "Cmts.User" user "User.Comments")
		(21 "Eco1.User" user "User.Eco1")
		(23 "Eco2.User" user "User.Eco2")
		(25 "Edge.Cuts" user "Board Geometry/Outline")
		(27 "Margin" user)
		(31 "F.CrtYd" user "Package Geometry/Place Bound Top")
		(29 "B.CrtYd" user "Package Geometry/Place Bound Bottom")
		(35 "F.Fab" user "Ref Des/Assembly Top")
		(33 "B.Fab" user "Ref Des/Assembly Bottom")
	)
	(footprint ""
		(layer "B.Cu")
		(at 59.649868 -288.299906 90)
		(property "Reference" "C2941"
			(at 0 0 90)
			(layer "B.SilkS")
			(hide yes)
			(effects
				(font
					(size 1.27 1.27)
				)
				(justify mirror)
			)
		)
		(property "Value" ""
			(at 0 0 90)
			(layer "B.Fab")
			(effects
				(font
					(size 1.27 1.27)
				)
				(justify mirror)
			)
		)
		(duplicate_pad_numbers_are_jumpers no)
		(fp_line
			(start 0.299974 -0.150114)
			(end -0.299974 -0.150114)
			(stroke
				(width 0.1)
				(type default)
			)
			(layer "B.Fab")
		)
		(fp_line
			(start -0.299974 -0.150114)
			(end -0.299974 0.150114)
			(stroke
				(width 0.1)
				(type default)
			)
			(layer "B.Fab")
		)
		(fp_line
			(start 0.299974 0.150114)
			(end 0.299974 -0.150114)
			(stroke
				(width 0.1)
				(type default)
			)
			(layer "B.Fab")
		)
		(fp_line
			(start -0.299974 0.150114)
			(end 0.299974 0.150114)
			(stroke
				(width 0.1)
				(type default)
			)
			(layer "B.Fab")
		)
		(pad "1" smd rect
			(at 0.2667 0 270)
			(size 0.3048 0.381)
			(layers "B.Cu" "B.Mask" "B.Paste")
			(net "P1V25_PEX0")
		)
		(pad "2" smd rect
			(at -0.2667 0 270)
			(size 0.3048 0.381)
			(layers "B.Cu" "B.Mask" "B.Paste")
			(net "GND")
		)
	)
	(footprint ""
		(layer "B.Cu")
		(at 60.599828 -299.699934 -90)
		(property "Reference" "C1229"
			(at 0 0 90)
			(layer "B.SilkS")
			(hide yes)
			(effects
				(font
					(size 1.27 1.27)
				)
				(justify mirror)
			)
		)
		(property "Value" ""
			(at 0 0 90)
			(layer "B.Fab")
			(effects
				(font
					(size 1.27 1.27)
				)
				(justify mirror)
			)
		)
		(duplicate_pad_numbers_are_jumpers no)
		(fp_line
			(start -0.299974 0.150114)
			(end 0.299974 0.150114)
			(stroke
				(width 0.1)
				(type default)
			)
			(layer "B.Fab")
		)
		(fp_line
			(start 0.299974 0.150114)
			(end 0.299974 -0.150114)
			(stroke
				(width 0.1)
				(type default)
			)
			(layer "B.Fab")
		)
		(fp_line
			(start -0.299974 -0.150114)
			(end -0.299974 0.150114)
			(stroke
				(width 0.1)
				(type default)
			)
			(layer "B.Fab")
		)
		(fp_line
			(start 0.299974 -0.150114)
			(end -0.299974 -0.150114)
			(stroke
				(width 0.1)
				(type default)
			)
			(layer "B.Fab")
		)
		(pad "1" smd rect
			(at 0.2667 0 90)
			(size 0.3048 0.381)
			(layers "B.Cu" "B.Mask" "B.Paste")
			(net "P0V8_SERDES_VDDA_PEX0")
		)
		(pad "2" smd rect
			(at -0.2667 0 90)
			(size 0.3048 0.381)
			(layers "B.Cu" "B.Mask" "B.Paste")
			(net "GND")
		)
	)
	(footprint ""
		(layer "B.Cu")
		(at 276.649688 -298.27474)
		(property "Reference" "C3358"
			(at 0 0 0)
			(layer "B.SilkS")
			(hide yes)
			(effects
				(font
					(size 1.27 1.27)
				)
				(justify mirror)
			)
		)
		(property "Value" ""
			(at 0 0 0)
			(layer "B.Fab")
			(effects
				(font
					(size 1.27 1.27)
				)
				(justify mirror)
			)
		)
		(duplicate_pad_numbers_are_jumpers no)
		(fp_line
			(start -0.299974 -0.150114)
			(end -0.299974 0.150114)
			(stroke
				(width 0.1)
				(type default)
			)
			(layer "B.Fab")
		)
		(fp_line
			(start -0.299974 0.150114)
			(end 0.299974 0.150114)
			(stroke
				(width 0.1)
				(type default)
			)
			(layer "B.Fab")
		)
		(fp_line
			(start 0.299974 -0.150114)
			(end -0.299974 -0.150114)
			(stroke
				(width 0.1)
				(type default)
			)
			(layer "B.Fab")
		)
		(fp_line
			(start 0.299974 0.150114)
			(end 0.299974 -0.150114)
			(stroke
				(width 0.1)
				(type default)
			)
			(layer "B.Fab")
		)
		(pad "1" smd rect
			(at 0.2667 0 180)
			(size 0.3048 0.381)
			(layers "B.Cu" "B.Mask" "B.Paste")
			(net "P1V8_VDDA_PEX2")
		)
		(pad "2" smd rect
			(at -0.2667 0 180)
			(size 0.3048 0.381)
			(layers "B.Cu" "B.Mask" "B.Paste")
			(net "GND")
		)
	)
	(footprint ""
		(layer "B.Cu")
		(at 77.541882 -100.056696 180)
		(property "Reference" "R77"
			(at 0 0 0)
			(layer "B.SilkS")
			(hide yes)
			(effects
				(font
					(size 1.27 1.27)
				)
				(justify mirror)
			)
		)
		(property "Value" ""
			(at 0 0 0)
			(layer "B.Fab")
			(effects
				(font
					(size 1.27 1.27)
				)
				(justify mirror)
			)
		)
		(duplicate_pad_numbers_are_jumpers no)
		(fp_line
			(start 0.7874 0.4064)
			(end 0.7874 -0.4064)
			(stroke
				(width 0.1524)
				(type default)
			)
			(layer "B.SilkS")
		)
		(fp_line
			(start 0.7874 -0.4064)
			(end -0.7874 -0.4064)
			(stroke
				(width 0.1524)
				(type default)
			)
			(layer "B.SilkS")
		)
		(fp_line
			(start -0.7874 0.4064)
			(end 0.7874 0.4064)
			(stroke
				(width 0.1524)
				(type default)
			)
			(layer "B.SilkS")
		)
		(fp_line
			(start -0.7874 -0.4064)
			(end -0.7874 0.4064)
			(stroke
				(width 0.1524)
				(type default)
			)
			(layer "B.SilkS")
		)
		(fp_line
			(start 0.67945 0.3048)
			(end 0.67945 -0.305054)
			(stroke
				(width 0.1)
				(type default)
			)
			(layer "B.Fab")
		)
		(fp_line
			(start 0.67945 -0.305054)
			(end 0.12065 -0.305054)
			(stroke
				(width 0.1)
				(type default)
			)
			(layer "B.Fab")
		)
		(fp_line
			(start 0.12065 0.3048)
			(end 0.67945 0.3048)
			(stroke
				(width 0.1)
				(type default)
			)
			(layer "B.Fab")
		)
		(fp_line
			(start 0.12065 0.2794)
			(end 0.12065 0.3048)
			(stroke
				(width 0.1)
				(type default)
			)
			(layer "B.Fab")
		)
		(fp_line
			(start 0.12065 -0.2794)
			(end -0.12065 -0.2794)
			(stroke
				(width 0.1)
				(type default)
			)
			(layer "B.Fab")
		)
		(fp_line
			(start 0.12065 -0.305054)
			(end 0.12065 -0.2794)
			(stroke
				(width 0.1)
				(type default)
			)
			(layer "B.Fab")
		)
		(fp_line
			(start -0.120396 0.3048)
			(end -0.120396 0.2794)
			(stroke
				(width 0.1)
				(type default)
			)
			(layer "B.Fab")
		)
		(fp_line
			(start -0.120396 0.2794)
			(end 0.12065 0.2794)
			(stroke
				(width 0.1)
				(type default)
			)
			(layer "B.Fab")
		)
		(fp_line
			(start -0.12065 -0.2794)
			(end -0.12065 -0.3048)
			(stroke
				(width 0.1)
				(type default)
			)
			(layer "B.Fab")
		)
		(fp_line
			(start -0.12065 -0.3048)
			(end -0.67945 -0.3048)
			(stroke
				(width 0.1)
				(type default)
			)
			(layer "B.Fab")
		)
		(fp_line
			(start -0.67945 0.3048)
			(end -0.120396 0.3048)
			(stroke
				(width 0.1)
				(type default)
			)
			(layer "B.Fab")
		)
		(fp_line
			(start -0.67945 -0.3048)
			(end -0.67945 0.3048)
			(stroke
				(width 0.1)
				(type default)
			)
			(layer "B.Fab")
		)
		(pad "1" smd circle
			(at 0.40005 0)
			(size 0 0)
			(layers "B.Cu" "B.Mask" "B.Paste")
			(net "NIC1_SLOT_ID0")
		)
		(pad "2" smd circle
			(at -0.40005 0)
			(size 0 0)
			(layers "B.Cu" "B.Mask" "B.Paste")
			(net "GND")
		)
	)
	(footprint ""
		(layer "B.Cu")
		(at 341.293958 -218.787218 -90)
		(property "Reference" "C2069"
			(at 0 0 90)
			(layer "B.SilkS")
			(hide yes)
			(effects
				(font
					(size 1.27 1.27)
				)
				(justify mirror)
			)
		)
		(property "Value" ""
			(at 0 0 90)
			(layer "B.Fab")
			(effects
				(font
					(size 1.27 1.27)
				)
				(justify mirror)
			)
		)
		(duplicate_pad_numbers_are_jumpers no)
		(fp_line
			(start -0.69215 0.2921)
			(end 0.69215 0.2921)
			(stroke
				(width 0.1524)
				(type default)
			)
			(layer "B.SilkS")
		)
		(fp_line
			(start 0.69215 0.2921)
			(end 0.69215 -0.2921)
			(stroke
				(width 0.1524)
				(type default)
			)
			(layer "B.SilkS")
		)
		(fp_line
			(start -0.69215 -0.2921)
			(end -0.69215 0.2921)
			(stroke
				(width 0.1524)
				(type default)
			)
			(layer "B.SilkS")
		)
		(fp_line
			(start 0.69215 -0.2921)
			(end -0.69215 -0.2921)
			(stroke
				(width 0.1524)
				(type default)
			)
			(layer "B.SilkS")
		)
		(fp_line
			(start -0.51435 0.2794)
			(end 0.51435 0.2794)
			(stroke
				(width 0.1)
				(type default)
			)
			(layer "B.Fab")
		)
		(fp_line
			(start 0.51435 0.2794)
			(end 0.51435 -0.2794)
			(stroke
				(width 0.1)
				(type default)
			)
			(layer "B.Fab")
		)
		(fp_line
			(start -0.51435 -0.2794)
			(end -0.51435 0.2794)
			(stroke
				(width 0.1)
				(type default)
			)
			(layer "B.Fab")
		)
		(fp_line
			(start 0.51435 -0.2794)
			(end -0.51435 -0.2794)
			(stroke
				(width 0.1)
				(type default)
			)
			(layer "B.Fab")
		)
		(pad "1" smd circle
			(at 0.40005 0 90)
			(size 0 0)
			(layers "B.Cu" "B.Mask" "B.Paste")
			(net "P3V3_VCC_FPGA_CORE")
		)
		(pad "2" smd circle
			(at -0.40005 0 90)
			(size 0 0)
			(layers "B.Cu" "B.Mask" "B.Paste")
			(net "GND")
		)
		(zone
			(layer "B.Cu")
			(hatch none 0.5)
			(connect_pads
				(clearance 0)
			)
			(min_thickness 0.25)
			(keepout
				(tracks not_allowed)
				(vias allowed)
				(pads allowed)
				(copperpour not_allowed)
				(footprints allowed)
			)
			(placement
				(enabled no)
				(sheetname "")
			)
			(fill
				(thermal_gap 0.5)
				(thermal_bridge_width 0.5)
				(island_removal_mode 0)
			)
			(polygon
				(pts
					(xy 341.206328 -218.596718) (xy 341.148162 -218.688158) (xy 341.148162 -218.887548) (xy 341.206328 -218.977718)
					(xy 341.381588 -218.977718) (xy 341.440008 -218.887548) (xy 341.440008 -218.688158) (xy 341.381842 -218.596718)
				)
			)
		)
	)
	(footprint ""
		(layer "B.Cu")
		(at 62.499748 -301.599854 -90)
		(property "Reference" "C1233"
			(at 0 0 90)
			(layer "B.SilkS")
			(hide yes)
			(effects
				(font
					(size 1.27 1.27)
				)
				(justify mirror)
			)
		)
		(property "Value" ""
			(at 0 0 90)
			(layer "B.Fab")
			(effects
				(font
					(size 1.27 1.27)
				)
				(justify mirror)
			)
		)
		(duplicate_pad_numbers_are_jumpers no)
		(fp_line
			(start -0.299974 0.150114)
			(end 0.299974 0.150114)
			(stroke
				(width 0.1)
				(type default)
			)
			(layer "B.Fab")
		)
		(fp_line
			(start 0.299974 0.150114)
			(end 0.299974 -0.150114)
			(stroke
				(width 0.1)
				(type default)
			)
			(layer "B.Fab")
		)
		(fp_line
			(start -0.299974 -0.150114)
			(end -0.299974 0.150114)
			(stroke
				(width 0.1)
				(type default)
			)
			(layer "B.Fab")
		)
		(fp_line
			(start 0.299974 -0.150114)
			(end -0.299974 -0.150114)
			(stroke
				(width 0.1)
				(type default)
			)
			(layer "B.Fab")
		)
		(pad "1" smd rect
			(at 0.2667 0 90)
			(size 0.3048 0.381)
			(layers "B.Cu" "B.Mask" "B.Paste")
			(net "P0V8_SERDES_VDDA_PEX0")
		)
		(pad "2" smd rect
			(at -0.2667 0 90)
			(size 0.3048 0.381)
			(layers "B.Cu" "B.Mask" "B.Paste")
			(net "GND")
		)
	)
	(footprint ""
		(layer "B.Cu")
		(at 404.30704 -138.557 90)
		(property "Reference" "C947"
			(at 0 0 90)
			(layer "B.SilkS")
			(hide yes)
			(effects
				(font
					(size 1.27 1.27)
				)
				(justify mirror)
			)
		)
		(property "Value" ""
			(at 0 0 90)
			(layer "B.Fab")
			(effects
				(font
					(size 1.27 1.27)
				)
				(justify mirror)
			)
		)
		(duplicate_pad_numbers_are_jumpers no)
		(fp_line
			(start 0.7874 -0.4064)
			(end -0.7874 -0.4064)
			(stroke
				(width 0.1524)
				(type default)
			)
			(layer "B.SilkS")
		)
		(fp_line
			(start -0.7874 -0.4064)
			(end -0.7874 0.4064)
			(stroke
				(width 0.1524)
				(type default)
			)
			(layer "B.SilkS")
		)
		(fp_line
			(start 0.7874 0.4064)
			(end 0.7874 -0.4064)
			(stroke
				(width 0.1524)
				(type default)
			)
			(layer "B.SilkS")
		)
		(fp_line
			(start -0.7874 0.4064)
			(end 0.7874 0.4064)
			(stroke
				(width 0.1524)
				(type default)
			)
			(layer "B.SilkS")
		)
		(fp_line
			(start 0.67945 -0.305054)
			(end 0.12065 -0.305054)
			(stroke
				(width 0.1)
				(type default)
			)
			(layer "B.Fab")
		)
		(fp_line
			(start 0.12065 -0.305054)
			(end 0.12065 -0.2794)
			(stroke
				(width 0.1)
				(type default)
			)
			(layer "B.Fab")
		)
		(fp_line
			(start -0.12065 -0.3048)
			(end -0.67945 -0.3048)
			(stroke
				(width 0.1)
				(type default)
			)
			(layer "B.Fab")
		)
		(fp_line
			(start -0.67945 -0.3048)
			(end -0.67945 0.3048)
			(stroke
				(width 0.1)
				(type default)
			)
			(layer "B.Fab")
		)
		(fp_line
			(start 0.12065 -0.2794)
			(end -0.12065 -0.2794)
			(stroke
				(width 0.1)
				(type default)
			)
			(layer "B.Fab")
		)
		(fp_line
			(start -0.12065 -0.2794)
			(end -0.12065 -0.3048)
			(stroke
				(width 0.1)
				(type default)
			)
			(layer "B.Fab")
		)
		(fp_line
			(start 0.12065 0.2794)
			(end 0.12065 0.3048)
			(stroke
				(width 0.1)
				(type default)
			)
			(layer "B.Fab")
		)
		(fp_line
			(start -0.120396 0.2794)
			(end 0.12065 0.2794)
			(stroke
				(width 0.1)
				(type default)
			)
			(layer "B.Fab")
		)
		(fp_line
			(start 0.67945 0.3048)
			(end 0.67945 -0.305054)
			(stroke
				(width 0.1)
				(type default)
			)
			(layer "B.Fab")
		)
		(fp_line
			(start 0.12065 0.3048)
			(end 0.67945 0.3048)
			(stroke
				(width 0.1)
				(type default)
			)
			(layer "B.Fab")
		)
		(fp_line
			(start -0.120396 0.3048)
			(end -0.120396 0.2794)
			(stroke
				(width 0.1)
				(type default)
			)
			(layer "B.Fab")
		)
		(fp_line
			(start -0.67945 0.3048)
			(end -0.120396 0.3048)
			(stroke
				(width 0.1)
				(type default)
			)
			(layer "B.Fab")
		)
		(pad "1" smd circle
			(at 0.40005 0 270)
			(size 0 0)
			(layers "B.Cu" "B.Mask" "B.Paste")
			(net "P3V3_AUX")
		)
		(pad "2" smd circle
			(at -0.40005 0 270)
			(size 0 0)
			(layers "B.Cu" "B.Mask" "B.Paste")
			(net "GND")
		)
	)
	(footprint ""
		(layer "B.Cu")
		(at 306.226718 -299.2247 90)
		(property "Reference" "R1381"
			(at 0 0 90)
			(layer "B.SilkS")
			(hide yes)
			(effects
				(font
					(size 1.27 1.27)
				)
				(justify mirror)
			)
		)
		(property "Value" ""
			(at 0 0 90)
			(layer "B.Fab")
			(effects
				(font
					(size 1.27 1.27)
				)
				(justify mirror)
			)
		)
		(duplicate_pad_numbers_are_jumpers no)
		(fp_line
			(start 0.7874 -0.4064)
			(end -0.7874 -0.4064)
			(stroke
				(width 0.1524)
				(type default)
			)
			(layer "B.SilkS")
		)
		(fp_line
			(start -0.7874 -0.4064)
			(end -0.7874 0.4064)
			(stroke
				(width 0.1524)
				(type default)
			)
			(layer "B.SilkS")
		)
		(fp_line
			(start 0.7874 0.4064)
			(end 0.7874 -0.4064)
			(stroke
				(width 0.1524)
				(type default)
			)
			(layer "B.SilkS")
		)
		(fp_line
			(start -0.7874 0.4064)
			(end 0.7874 0.4064)
			(stroke
				(width 0.1524)
				(type default)
			)
			(layer "B.SilkS")
		)
		(fp_line
			(start 0.67945 -0.305054)
			(end 0.12065 -0.305054)
			(stroke
				(width 0.1)
				(type default)
			)
			(layer "B.Fab")
		)
		(fp_line
			(start 0.12065 -0.305054)
			(end 0.12065 -0.2794)
			(stroke
				(width 0.1)
				(type default)
			)
			(layer "B.Fab")
		)
		(fp_line
			(start -0.12065 -0.3048)
			(end -0.67945 -0.3048)
			(stroke
				(width 0.1)
				(type default)
			)
			(layer "B.Fab")
		)
		(fp_line
			(start -0.67945 -0.3048)
			(end -0.67945 0.3048)
			(stroke
				(width 0.1)
				(type default)
			)
			(layer "B.Fab")
		)
		(fp_line
			(start 0.12065 -0.2794)
			(end -0.12065 -0.2794)
			(stroke
				(width 0.1)
				(type default)
			)
			(layer "B.Fab")
		)
		(fp_line
			(start -0.12065 -0.2794)
			(end -0.12065 -0.3048)
			(stroke
				(width 0.1)
				(type default)
			)
			(layer "B.Fab")
		)
		(fp_line
			(start 0.12065 0.2794)
			(end 0.12065 0.3048)
			(stroke
				(width 0.1)
				(type default)
			)
			(layer "B.Fab")
		)
		(fp_line
			(start -0.120396 0.2794)
			(end 0.12065 0.2794)
			(stroke
				(width 0.1)
				(type default)
			)
			(layer "B.Fab")
		)
		(fp_line
			(start 0.67945 0.3048)
			(end 0.67945 -0.305054)
			(stroke
				(width 0.1)
				(type default)
			)
			(layer "B.Fab")
		)
		(fp_line
			(start 0.12065 0.3048)
			(end 0.67945 0.3048)
			(stroke
				(width 0.1)
				(type default)
			)
			(layer "B.Fab")
		)
		(fp_line
			(start -0.120396 0.3048)
			(end -0.120396 0.2794)
			(stroke
				(width 0.1)
				(type default)
			)
			(layer "B.Fab")
		)
		(fp_line
			(start -0.67945 0.3048)
			(end -0.120396 0.3048)
			(stroke
				(width 0.1)
				(type default)
			)
			(layer "B.Fab")
		)
		(pad "1" smd circle
			(at 0.40005 0 270)
			(size 0 0)
			(layers "B.Cu" "B.Mask" "B.Paste")
			(net "PEX2_ADCTEMP_VINP1")
		)
		(pad "2" smd circle
			(at -0.40005 0 270)
			(size 0 0)
			(layers "B.Cu" "B.Mask" "B.Paste")
			(net "GND")
		)
	)
	(footprint ""
		(layer "B.Cu")
		(at 172.424852 -286.399732 90)
		(property "Reference" "C3134"
			(at 0 0 90)
			(layer "B.SilkS")
			(hide yes)
			(effects
				(font
					(size 1.27 1.27)
				)
				(justify mirror)
			)
		)
		(property "Value" ""
			(at 0 0 90)
			(layer "B.Fab")
			(effects
				(font
					(size 1.27 1.27)
				)
				(justify mirror)
			)
		)
		(duplicate_pad_numbers_are_jumpers no)
		(fp_line
			(start 0.299974 -0.150114)
			(end -0.299974 -0.150114)
			(stroke
				(width 0.1)
				(type default)
			)
			(layer "B.Fab")
		)
		(fp_line
			(start -0.299974 -0.150114)
			(end -0.299974 0.150114)
			(stroke
				(width 0.1)
				(type default)
			)
			(layer "B.Fab")
		)
		(fp_line
			(start 0.299974 0.150114)
			(end 0.299974 -0.150114)
			(stroke
				(width 0.1)
				(type default)
			)
			(layer "B.Fab")
		)
		(fp_line
			(start -0.299974 0.150114)
			(end 0.299974 0.150114)
			(stroke
				(width 0.1)
				(type default)
			)
			(layer "B.Fab")
		)
		(pad "1" smd rect
			(at 0.2667 0 270)
			(size 0.3048 0.381)
			(layers "B.Cu" "B.Mask" "B.Paste")
			(net "P1V25_SERDES_VDDPLL_PEX1")
		)
		(pad "2" smd rect
			(at -0.2667 0 270)
			(size 0.3048 0.381)
			(layers "B.Cu" "B.Mask" "B.Paste")
			(net "GND")
		)
	)
	(footprint ""
		(layer "B.Cu")
		(at 65.349882 -292.099746 90)
		(property "Reference" "C1167"
			(at 0 0 90)
			(layer "B.SilkS")
			(hide yes)
			(effects
				(font
					(size 1.27 1.27)
				)
				(justify mirror)
			)
		)
		(property "Value" ""
			(at 0 0 90)
			(layer "B.Fab")
			(effects
				(font
					(size 1.27 1.27)
				)
				(justify mirror)
			)
		)
		(duplicate_pad_numbers_are_jumpers no)
		(fp_line
			(start 0.299974 -0.150114)
			(end -0.299974 -0.150114)
			(stroke
				(width 0.1)
				(type default)
			)
			(layer "B.Fab")
		)
		(fp_line
			(start -0.299974 -0.150114)
			(end -0.299974 0.150114)
			(stroke
				(width 0.1)
				(type default)
			)
			(layer "B.Fab")
		)
		(fp_line
			(start 0.299974 0.150114)
			(end 0.299974 -0.150114)
			(stroke
				(width 0.1)
				(type default)
			)
			(layer "B.Fab")
		)
		(fp_line
			(start -0.299974 0.150114)
			(end 0.299974 0.150114)
			(stroke
				(width 0.1)
				(type default)
			)
			(layer "B.Fab")
		)
		(pad "1" smd rect
			(at 0.2667 0 270)
			(size 0.3048 0.381)
			(layers "B.Cu" "B.Mask" "B.Paste")
			(net "P0V8_SERDES_VDDA_PEX0")
		)
		(pad "2" smd rect
			(at -0.2667 0 270)
			(size 0.3048 0.381)
			(layers "B.Cu" "B.Mask" "B.Paste")
			(net "GND")
		)
	)
)
